#ISCELL
  mstr_symbols cad_note *
  *
#ISCELL
  mstr_symbols design_note *
  *
#ISCELL
  mstr_symbols intel_corp_bpage *
  *
#ISCELL
  mstr_standard offpage *
  page169_i103
#ISCELL
  mstr_standard offpage *
  page169_i105
#CELL
  mstr_discrete res *
  page169_i106
#ISCELL
  mstr_symbols gnd *
  page169_i107
#CELL
  mstr_discrete cap *
  page169_i108
#ISCELL
  mstr_symbols gnd *
  page169_i109
#CELL
  mstr_discrete res *
  page169_i115
#ISCELL
  mstr_symbols p5v_stby *
  page169_i119
#ISCELL
  mstr_symbols p1v05_pch_stby *
  page169_i121
#CELL
  mstr_discrete res *
  page169_i126
#ISCELL
  mstr_symbols p3v3_stby *
  page169_i131
#ISCELL
  mstr_symbols p12v_stby *
  page169_i132
#ISCELL
  mstr_standard offpage *
  page169_i138
#CELL
  mstr_discrete cap *
  page169_i139
#CELL
  mstr_discrete res *
  page169_i141
#ISCELL
  mstr_symbols gnd *
  page169_i143
#ISCELL
  mstr_symbols p5v *
  page169_i144
#ISCELL
  mstr_standard offpage *
  page169_i145
#CELL
  mstr_discrete cap *
  page169_i146
#CELL
  mstr_discrete res *
  page169_i148
#ISCELL
  mstr_symbols gnd *
  page169_i150
#ISCELL
  mstr_symbols p3v3 *
  page169_i151
#ISCELL
  mstr_standard offpage *
  page169_i152
#CELL
  mstr_discrete cap *
  page169_i153
#ISCELL
  mstr_symbols pvnn_pch_stby *
  page169_i154
#CELL
  mstr_discrete ferrite *
  page169_i155
#ISCELL
  mstr_symbols gnd *
  page169_i156
#CELL
  mstr_discrete fet_n_dual *
  page169_i157
#ISCELL
  mstr_symbols gnd *
  page169_i160
#ISCELL
  mstr_standard offpage *
  page169_i161
#CELL
  mstr_discrete fet_n_dual *
  page169_i162
#CELL
  mstr_discrete res *
  page169_i163
#CELL
  mstr_discrete res *
  page169_i164
#ISCELL
  mstr_symbols p3v3_stby *
  page169_i165
#ISCELL
  mstr_symbols p3v3_stby *
  page169_i166
#CELL
  w_hdl 1k82r2f-1-gp *
  page169_i169
#CELL
  w_hdl 1k82r2f-1-gp *
  page169_i170
#CELL
  w_hdl 649r2f-gp *
  page169_i171
#CELL
  mstr_discrete res *
  page169_i172
#CELL
  mstr_discrete res *
  page169_i173
#ISCELL
  mstr_standard offpage *
  page169_i55
#CELL
  mstr_discrete cap *
  page169_i56
#CELL
  mstr_discrete ferrite *
  page169_i57
#ISCELL
  mstr_symbols gnd *
  page169_i58
#ISCELL
  mstr_standard offpage *
  page169_i67
#CELL
  mstr_discrete cap *
  page169_i68
#ISCELL
  mstr_symbols gnd *
  page169_i71
#ISCELL
  mstr_standard offpage *
  page169_i79
#CELL
  mstr_discrete cap *
  page169_i80
#CELL
  mstr_discrete res *
  page169_i82
#ISCELL
  mstr_symbols gnd *
  page169_i84
#ISCELL
  mstr_standard offpage *
  page169_i85
#CELL
  mstr_discrete cap *
  page169_i86
#CELL
  mstr_discrete res *
  page169_i88
#ISCELL
  mstr_symbols gnd *
  page169_i90
